(kicad_pcb
	(version 20260206)
	(generator "pcbnew")
	(generator_version "10.0")
	(general
		(thickness 1.6)
		(legacy_teardrops no)
	)
	(paper "A4")
	(title_block
		(title "baseboard — 13948-1b.1110WZS1818.brd")
		(comment 1 "Honey Badger (Wiwynn) / footprints 1773-1782 of 2523")
	)
	(layers
		(0 "F.Cu" signal "TOP")
		(4 "In1.Cu" signal "L2GND")
		(6 "In2.Cu" signal "L3")
		(8 "In3.Cu" signal "L4VCC")
		(10 "In4.Cu" signal "L5VCC")
		(12 "In5.Cu" signal "L6")
		(14 "In6.Cu" signal "L7GND")
		(2 "B.Cu" signal "BOTTOM")
		(9 "F.Adhes" user "F.Adhesive")
		(11 "B.Adhes" user "B.Adhesive")
		(13 "F.Paste" user "Package Geometry/Pastemask Top")
		(15 "B.Paste" user "Package Geometry/Pastemask Bottom")
		(5 "F.SilkS" user "Ref Des/Silkscreen Top")
		(7 "B.SilkS" user "Ref Des/Silkscreen Bottom")
		(1 "F.Mask" user "Board Geometry/Soldermask Top")
		(3 "B.Mask" user "Board Geometry/Soldermask Bottom")
		(17 "Dwgs.User" user "User.Drawings")
		(19 "Cmts.User" user "User.Comments")
		(21 "Eco1.User" user "User.Eco1")
		(23 "Eco2.User" user "User.Eco2")
		(25 "Edge.Cuts" user "Board Geometry/Outline")
		(27 "Margin" user)
		(31 "F.CrtYd" user "Package Geometry/Place Bound Top")
		(29 "B.CrtYd" user "Package Geometry/Place Bound Bottom")
		(35 "F.Fab" user "Ref Des/Assembly Top")
		(33 "B.Fab" user "Ref Des/Assembly Bottom")
	)
	(footprint ""
		(layer "B.Cu")
		(at 100.979986 -54.65572 -90)
		(property "Reference" "SC1003"
			(at 0 0 90)
			(layer "B.SilkS")
			(hide yes)
			(effects
				(font
					(size 1.27 1.27)
				)
				(justify mirror)
			)
		)
		(property "Value" "SCD1U16V2KX-3GP"
			(at -1.1811 -2.7051 270)
			(unlocked yes)
			(layer "B.Fab")
			(hide yes)
			(effects
				(font
					(size 1.016 1.016)
					(thickness 0.1524)
				)
				(justify mirror)
			)
		)
		(property "Device Type" "C402H22"
			(at -1.1811 -4.2291 270)
			(unlocked yes)
			(layer "B.Fab")
			(hide yes)
			(effects
				(font
					(size 1.016 1.016)
					(thickness 0.1524)
				)
				(justify mirror)
			)
		)
		(duplicate_pad_numbers_are_jumpers no)
		(fp_rect
			(start 0.4318 0.9525)
			(end -0.4318 -0.9525)
			(stroke
				(width 0)
				(type default)
			)
			(fill no)
			(layer "B.CrtYd")
		)
		(fp_rect
			(start 0.4318 0.9525)
			(end -0.4318 -0.9525)
			(stroke
				(width 0)
				(type default)
			)
			(fill no)
			(layer "B.Fab")
		)
		(pad "1" smd custom
			(at 0 -0.4445 90)
			(size 0.1524 0.1524)
			(layers "B.Cu" "B.Mask" "B.Paste")
			(net "P1V8_C")
			(options
				(clearance outline)
				(anchor circle)
			)
			(primitives
				(gr_poly
					(pts
						(arc
							(start 0.3048 0.2032)
							(mid 0.275042 0.275042)
							(end 0.2032 0.3048)
						)
						(arc
							(start -0.2032 0.3048)
							(mid -0.275042 0.275042)
							(end -0.3048 0.2032)
						)
						(arc
							(start -0.3048 -0.2032)
							(mid -0.275042 -0.275042)
							(end -0.2032 -0.3048)
						)
						(arc
							(start 0.2032 -0.3048)
							(mid 0.275042 -0.275042)
							(end 0.3048 -0.2032)
						)
					)
					(width 0)
					(fill yes)
				)
			)
		)
		(pad "2" smd custom
			(at 0 0.4445 90)
			(size 0.1524 0.1524)
			(layers "B.Cu" "B.Mask" "B.Paste")
			(net "GND")
			(options
				(clearance outline)
				(anchor circle)
			)
			(primitives
				(gr_poly
					(pts
						(arc
							(start 0.3048 0.2032)
							(mid 0.275042 0.275042)
							(end 0.2032 0.3048)
						)
						(arc
							(start -0.2032 0.3048)
							(mid -0.275042 0.275042)
							(end -0.3048 0.2032)
						)
						(arc
							(start -0.3048 -0.2032)
							(mid -0.275042 -0.275042)
							(end -0.2032 -0.3048)
						)
						(arc
							(start 0.2032 -0.3048)
							(mid 0.275042 -0.275042)
							(end 0.3048 -0.2032)
						)
					)
					(width 0)
					(fill yes)
				)
			)
		)
	)
	(footprint ""
		(layer "B.Cu")
		(at 118.872 -42.926 -90)
		(property "Reference" "SR653"
			(at 0 0 90)
			(layer "B.SilkS")
			(hide yes)
			(effects
				(font
					(size 1.27 1.27)
				)
				(justify mirror)
			)
		)
		(property "Value" "10KR2F-2-GP"
			(at -0.064008 -3.993896 270)
			(unlocked yes)
			(layer "B.Fab")
			(hide yes)
			(effects
				(font
					(size 1.016 1.016)
					(thickness 0.1524)
				)
				(justify mirror)
			)
		)
		(property "Device Type" "R402H16"
			(at -0.064008 -5.517896 270)
			(unlocked yes)
			(layer "B.Fab")
			(hide yes)
			(effects
				(font
					(size 1.016 1.016)
					(thickness 0.1524)
				)
				(justify mirror)
			)
		)
		(duplicate_pad_numbers_are_jumpers no)
		(fp_line
			(start -0.508 -0.9398)
			(end 0.508 -0.9398)
			(stroke
				(width 0.1524)
				(type default)
			)
			(layer "B.SilkS")
		)
		(fp_line
			(start 0.508 -0.9398)
			(end 0.508 0.9398)
			(stroke
				(width 0.1524)
				(type default)
			)
			(layer "B.SilkS")
		)
		(fp_rect
			(start 0.508 0.9398)
			(end -0.508 -0.9398)
			(stroke
				(width 0)
				(type default)
			)
			(fill no)
			(layer "B.CrtYd")
		)
		(fp_rect
			(start 0.508 0.9398)
			(end -0.508 -0.9398)
			(stroke
				(width 0)
				(type default)
			)
			(fill no)
			(layer "B.Fab")
		)
		(pad "1" smd custom
			(at 0 -0.4445 90)
			(size 0.1397 0.1397)
			(layers "B.Cu" "B.Mask" "B.Paste")
			(net "P1V8_C")
			(options
				(clearance outline)
				(anchor circle)
			)
			(primitives
				(gr_poly
					(pts
						(arc
							(start -0.1778 0.2794)
							(mid -0.249642 0.249642)
							(end -0.2794 0.1778)
						)
						(arc
							(start -0.2794 -0.1778)
							(mid -0.249642 -0.249642)
							(end -0.1778 -0.2794)
						)
						(arc
							(start 0.1778 -0.2794)
							(mid 0.249642 -0.249642)
							(end 0.2794 -0.1778)
						)
						(arc
							(start 0.2794 0.1778)
							(mid 0.249642 0.249642)
							(end 0.1778 0.2794)
						)
					)
					(width 0)
					(fill yes)
				)
			)
		)
		(pad "2" smd custom
			(at 0 0.4445 90)
			(size 0.1397 0.1397)
			(layers "B.Cu" "B.Mask" "B.Paste")
			(net "SYS_HB_LED")
			(options
				(clearance outline)
				(anchor circle)
			)
			(primitives
				(gr_poly
					(pts
						(arc
							(start -0.1778 0.2794)
							(mid -0.249642 0.249642)
							(end -0.2794 0.1778)
						)
						(arc
							(start -0.2794 -0.1778)
							(mid -0.249642 -0.249642)
							(end -0.1778 -0.2794)
						)
						(arc
							(start 0.1778 -0.2794)
							(mid 0.249642 -0.249642)
							(end 0.2794 -0.1778)
						)
						(arc
							(start 0.2794 0.1778)
							(mid 0.249642 0.249642)
							(end 0.1778 0.2794)
						)
					)
					(width 0)
					(fill yes)
				)
			)
		)
	)
	(footprint ""
		(layer "B.Cu")
		(at 106.735626 -38.55974)
		(property "Reference" "STP76"
			(at 0 0 0)
			(layer "B.SilkS")
			(hide yes)
			(effects
				(font
					(size 1.27 1.27)
				)
				(justify mirror)
			)
		)
		(property "Value" "TPAD28"
			(at -0.0127 -1.8034 0)
			(unlocked yes)
			(layer "B.Fab")
			(hide yes)
			(effects
				(font
					(size 1.016 1.016)
					(thickness 0.1524)
				)
				(justify mirror)
			)
		)
		(property "Device Type" "TPAD28"
			(at -0.0127 -3.3274 0)
			(unlocked yes)
			(layer "B.Fab")
			(hide yes)
			(effects
				(font
					(size 1.016 1.016)
					(thickness 0.1524)
				)
				(justify mirror)
			)
		)
		(duplicate_pad_numbers_are_jumpers no)
		(fp_poly
			(pts
				(arc
					(start 0.3556 0)
					(mid -0.3556 0)
					(end 0.3556 0)
				)
			)
			(stroke
				(width 0)
				(type default)
			)
			(fill no)
			(layer "B.CrtYd")
		)
		(fp_poly
			(pts
				(arc
					(start 0.6096 0)
					(mid -0.6096 0)
					(end 0.6096 0)
				)
			)
			(stroke
				(width 0)
				(type default)
			)
			(fill no)
			(layer "B.Fab")
		)
		(pad "1" smd circle
			(at 0 0 180)
			(size 0.7112 0.7112)
			(layers "B.Cu" "B.Mask" "B.Paste")
			(net "IOC_GPIO_7")
		)
	)
	(footprint ""
		(layer "B.Cu")
		(at 102.997 -226.949 -90)
		(property "Reference" "R668"
			(at 0 0 90)
			(layer "B.SilkS")
			(hide yes)
			(effects
				(font
					(size 1.27 1.27)
				)
				(justify mirror)
			)
		)
		(property "Value" "0R2J-2-GP"
			(at -0.064008 -3.993896 270)
			(unlocked yes)
			(layer "B.Fab")
			(hide yes)
			(effects
				(font
					(size 1.016 1.016)
					(thickness 0.1524)
				)
				(justify mirror)
			)
		)
		(property "Device Type" "R402H16"
			(at -0.064008 -5.517896 270)
			(unlocked yes)
			(layer "B.Fab")
			(hide yes)
			(effects
				(font
					(size 1.016 1.016)
					(thickness 0.1524)
				)
				(justify mirror)
			)
		)
		(duplicate_pad_numbers_are_jumpers no)
		(fp_line
			(start -0.508 -0.9398)
			(end 0.508 -0.9398)
			(stroke
				(width 0.1524)
				(type default)
			)
			(layer "B.SilkS")
		)
		(fp_line
			(start 0.508 -0.9398)
			(end 0.508 0.9398)
			(stroke
				(width 0.1524)
				(type default)
			)
			(layer "B.SilkS")
		)
		(fp_rect
			(start 0.508 0.9398)
			(end -0.508 -0.9398)
			(stroke
				(width 0)
				(type default)
			)
			(fill no)
			(layer "B.CrtYd")
		)
		(fp_rect
			(start 0.508 0.9398)
			(end -0.508 -0.9398)
			(stroke
				(width 0)
				(type default)
			)
			(fill no)
			(layer "B.Fab")
		)
		(pad "1" smd custom
			(at 0 -0.4445 90)
			(size 0.1397 0.1397)
			(layers "B.Cu" "B.Mask" "B.Paste")
			(net "SAS_FAULT_LED0")
			(options
				(clearance outline)
				(anchor circle)
			)
			(primitives
				(gr_poly
					(pts
						(arc
							(start -0.1778 0.2794)
							(mid -0.249642 0.249642)
							(end -0.2794 0.1778)
						)
						(arc
							(start -0.2794 -0.1778)
							(mid -0.249642 -0.249642)
							(end -0.1778 -0.2794)
						)
						(arc
							(start 0.1778 -0.2794)
							(mid 0.249642 -0.249642)
							(end 0.2794 -0.1778)
						)
						(arc
							(start 0.2794 0.1778)
							(mid 0.249642 0.249642)
							(end 0.1778 0.2794)
						)
					)
					(width 0)
					(fill yes)
				)
			)
		)
		(pad "2" smd custom
			(at 0 0.4445 90)
			(size 0.1397 0.1397)
			(layers "B.Cu" "B.Mask" "B.Paste")
			(net "SAS_HDD_LED_0")
			(options
				(clearance outline)
				(anchor circle)
			)
			(primitives
				(gr_poly
					(pts
						(arc
							(start -0.1778 0.2794)
							(mid -0.249642 0.249642)
							(end -0.2794 0.1778)
						)
						(arc
							(start -0.2794 -0.1778)
							(mid -0.249642 -0.249642)
							(end -0.1778 -0.2794)
						)
						(arc
							(start 0.1778 -0.2794)
							(mid 0.249642 -0.249642)
							(end 0.2794 -0.1778)
						)
						(arc
							(start 0.2794 0.1778)
							(mid 0.249642 0.249642)
							(end 0.1778 0.2794)
						)
					)
					(width 0)
					(fill yes)
				)
			)
		)
	)
	(footprint ""
		(layer "B.Cu")
		(at 107.07116 -31.369)
		(property "Reference" "STP52"
			(at 0 0 0)
			(layer "B.SilkS")
			(hide yes)
			(effects
				(font
					(size 1.27 1.27)
				)
				(justify mirror)
			)
		)
		(property "Value" "TPAD28"
			(at -0.0127 -1.8034 0)
			(unlocked yes)
			(layer "B.Fab")
			(hide yes)
			(effects
				(font
					(size 1.016 1.016)
					(thickness 0.1524)
				)
				(justify mirror)
			)
		)
		(property "Device Type" "TPAD28"
			(at -0.0127 -3.3274 0)
			(unlocked yes)
			(layer "B.Fab")
			(hide yes)
			(effects
				(font
					(size 1.016 1.016)
					(thickness 0.1524)
				)
				(justify mirror)
			)
		)
		(duplicate_pad_numbers_are_jumpers no)
		(fp_poly
			(pts
				(arc
					(start 0.3556 0)
					(mid -0.3556 0)
					(end 0.3556 0)
				)
			)
			(stroke
				(width 0)
				(type default)
			)
			(fill no)
			(layer "B.CrtYd")
		)
		(fp_poly
			(pts
				(arc
					(start 0.6096 0)
					(mid -0.6096 0)
					(end 0.6096 0)
				)
			)
			(stroke
				(width 0)
				(type default)
			)
			(fill no)
			(layer "B.Fab")
		)
		(pad "1" smd circle
			(at 0 0 180)
			(size 0.7112 0.7112)
			(layers "B.Cu" "B.Mask" "B.Paste")
			(net "SPARE2")
		)
	)
	(footprint ""
		(layer "B.Cu")
		(at 114.723926 -40.41648)
		(property "Reference" "STP20"
			(at 0 0 0)
			(layer "B.SilkS")
			(hide yes)
			(effects
				(font
					(size 1.27 1.27)
				)
				(justify mirror)
			)
		)
		(property "Value" "TPAD28"
			(at -0.0127 -1.8034 0)
			(unlocked yes)
			(layer "B.Fab")
			(hide yes)
			(effects
				(font
					(size 1.016 1.016)
					(thickness 0.1524)
				)
				(justify mirror)
			)
		)
		(property "Device Type" "TPAD28"
			(at -0.0127 -3.3274 0)
			(unlocked yes)
			(layer "B.Fab")
			(hide yes)
			(effects
				(font
					(size 1.016 1.016)
					(thickness 0.1524)
				)
				(justify mirror)
			)
		)
		(duplicate_pad_numbers_are_jumpers no)
		(fp_poly
			(pts
				(arc
					(start 0.3556 0)
					(mid -0.3556 0)
					(end 0.3556 0)
				)
			)
			(stroke
				(width 0)
				(type default)
			)
			(fill no)
			(layer "B.CrtYd")
		)
		(fp_poly
			(pts
				(arc
					(start 0.6096 0)
					(mid -0.6096 0)
					(end 0.6096 0)
				)
			)
			(stroke
				(width 0)
				(type default)
			)
			(fill no)
			(layer "B.Fab")
		)
		(pad "1" smd circle
			(at 0 0 180)
			(size 0.7112 0.7112)
			(layers "B.Cu" "B.Mask" "B.Paste")
			(net "IOC_GPIO_35")
		)
	)
	(footprint ""
		(layer "B.Cu")
		(at 90.95232 -46.8122)
		(property "Reference" "STP21"
			(at 0 0 0)
			(layer "B.SilkS")
			(hide yes)
			(effects
				(font
					(size 1.27 1.27)
				)
				(justify mirror)
			)
		)
		(property "Value" "TPAD28"
			(at -0.0127 -1.8034 0)
			(unlocked yes)
			(layer "B.Fab")
			(hide yes)
			(effects
				(font
					(size 1.016 1.016)
					(thickness 0.1524)
				)
				(justify mirror)
			)
		)
		(property "Device Type" "TPAD28"
			(at -0.0127 -3.3274 0)
			(unlocked yes)
			(layer "B.Fab")
			(hide yes)
			(effects
				(font
					(size 1.016 1.016)
					(thickness 0.1524)
				)
				(justify mirror)
			)
		)
		(duplicate_pad_numbers_are_jumpers no)
		(fp_poly
			(pts
				(arc
					(start 0.3556 0)
					(mid -0.3556 0)
					(end 0.3556 0)
				)
			)
			(stroke
				(width 0)
				(type default)
			)
			(fill no)
			(layer "B.CrtYd")
		)
		(fp_poly
			(pts
				(arc
					(start 0.6096 0)
					(mid -0.6096 0)
					(end 0.6096 0)
				)
			)
			(stroke
				(width 0)
				(type default)
			)
			(fill no)
			(layer "B.Fab")
		)
		(pad "1" smd circle
			(at 0 0 180)
			(size 0.7112 0.7112)
			(layers "B.Cu" "B.Mask" "B.Paste")
			(net "IOC_SIO_BLINK")
		)
	)
	(footprint ""
		(layer "B.Cu")
		(at 78.105 -25.019 -90)
		(property "Reference" "SR930"
			(at 0 0 90)
			(layer "B.SilkS")
			(hide yes)
			(effects
				(font
					(size 1.27 1.27)
				)
				(justify mirror)
			)
		)
		(property "Value" "4K7R2F-GP"
			(at -0.064008 -3.993896 270)
			(unlocked yes)
			(layer "B.Fab")
			(hide yes)
			(effects
				(font
					(size 1.016 1.016)
					(thickness 0.1524)
				)
				(justify mirror)
			)
		)
		(property "Device Type" "R402H16"
			(at -0.064008 -5.517896 270)
			(unlocked yes)
			(layer "B.Fab")
			(hide yes)
			(effects
				(font
					(size 1.016 1.016)
					(thickness 0.1524)
				)
				(justify mirror)
			)
		)
		(duplicate_pad_numbers_are_jumpers no)
		(fp_line
			(start -0.508 -0.9398)
			(end 0.508 -0.9398)
			(stroke
				(width 0.1524)
				(type default)
			)
			(layer "B.SilkS")
		)
		(fp_line
			(start 0.508 -0.9398)
			(end 0.508 0.9398)
			(stroke
				(width 0.1524)
				(type default)
			)
			(layer "B.SilkS")
		)
		(fp_rect
			(start 0.508 0.9398)
			(end -0.508 -0.9398)
			(stroke
				(width 0)
				(type default)
			)
			(fill no)
			(layer "B.CrtYd")
		)
		(fp_rect
			(start 0.508 0.9398)
			(end -0.508 -0.9398)
			(stroke
				(width 0)
				(type default)
			)
			(fill no)
			(layer "B.Fab")
		)
		(pad "1" smd custom
			(at 0 -0.4445 90)
			(size 0.1397 0.1397)
			(layers "B.Cu" "B.Mask" "B.Paste")
			(net "P3V3_STBY")
			(options
				(clearance outline)
				(anchor circle)
			)
			(primitives
				(gr_poly
					(pts
						(arc
							(start -0.1778 0.2794)
							(mid -0.249642 0.249642)
							(end -0.2794 0.1778)
						)
						(arc
							(start -0.2794 -0.1778)
							(mid -0.249642 -0.249642)
							(end -0.1778 -0.2794)
						)
						(arc
							(start 0.1778 -0.2794)
							(mid 0.249642 -0.249642)
							(end 0.2794 -0.1778)
						)
						(arc
							(start 0.2794 0.1778)
							(mid 0.249642 0.249642)
							(end 0.1778 0.2794)
						)
					)
					(width 0)
					(fill yes)
				)
			)
		)
		(pad "2" smd custom
			(at 0 0.4445 90)
			(size 0.1397 0.1397)
			(layers "B.Cu" "B.Mask" "B.Paste")
			(net "P3V3_STBY_R9")
			(options
				(clearance outline)
				(anchor circle)
			)
			(primitives
				(gr_poly
					(pts
						(arc
							(start -0.1778 0.2794)
							(mid -0.249642 0.249642)
							(end -0.2794 0.1778)
						)
						(arc
							(start -0.2794 -0.1778)
							(mid -0.249642 -0.249642)
							(end -0.1778 -0.2794)
						)
						(arc
							(start 0.1778 -0.2794)
							(mid 0.249642 -0.249642)
							(end 0.2794 -0.1778)
						)
						(arc
							(start 0.2794 0.1778)
							(mid 0.249642 0.249642)
							(end 0.1778 0.2794)
						)
					)
					(width 0)
					(fill yes)
				)
			)
		)
	)
	(footprint ""
		(layer "B.Cu")
		(at 68.599812 -23.39975)
		(property "Reference" ""
			(at 0 0 0)
			(layer "B.SilkS")
			(hide yes)
			(effects
				(font
					(size 1.27 1.27)
				)
				(justify mirror)
			)
		)
		(property "Value" "*"
			(at 5.5753 -0.4572 0)
			(unlocked yes)
			(layer "B.Fab")
			(hide yes)
			(effects
				(font
					(size 1.016 1.016)
					(thickness 0.1524)
				)
				(justify mirror)
			)
		)
		(duplicate_pad_numbers_are_jumpers no)
		(fp_poly
			(pts
				(arc
					(start 4.3053 0)
					(mid -4.3053 0)
					(end 4.3053 0)
				)
			)
			(stroke
				(width 0)
				(type default)
			)
			(fill no)
			(layer "B.CrtYd")
		)
		(fp_poly
			(pts
				(arc
					(start 4.3053 0)
					(mid -4.3053 0)
					(end 4.3053 0)
				)
			)
			(stroke
				(width 0)
				(type default)
			)
			(fill no)
			(layer "B.Fab")
		)
		(pad "1" smd custom
			(at 2.95275 0 180)
			(size 2.000013 2.000013)
			(layers "B.Cu" "B.Mask" "B.Paste")
			(net "Net_57")
			(options
				(clearance outline)
				(anchor circle)
			)
			(primitives
				(gr_poly
					(pts
						(arc
							(start 4.0005 -0.00254)
							(mid -4.000501 0)
							(end 4.0005 0.00254)
						)
						(arc
							(start 1.905 0.00254)
							(mid -1.905002 0)
							(end 1.905 -0.00254)
						)
					)
					(width 0)
					(fill yes)
				)
			)
		)
	)
	(footprint ""
		(layer "B.Cu")
		(at 108.373926 -53.00218 -90)
		(property "Reference" "SC999"
			(at 0 0 90)
			(layer "B.SilkS")
			(hide yes)
			(effects
				(font
					(size 1.27 1.27)
				)
				(justify mirror)
			)
		)
		(property "Value" "SCD1U16V2KX-3GP"
			(at -1.1811 -2.7051 270)
			(unlocked yes)
			(layer "B.Fab")
			(hide yes)
			(effects
				(font
					(size 1.016 1.016)
					(thickness 0.1524)
				)
				(justify mirror)
			)
		)
		(property "Device Type" "C402H22"
			(at -1.1811 -4.2291 270)
			(unlocked yes)
			(layer "B.Fab")
			(hide yes)
			(effects
				(font
					(size 1.016 1.016)
					(thickness 0.1524)
				)
				(justify mirror)
			)
		)
		(duplicate_pad_numbers_are_jumpers no)
		(fp_rect
			(start 0.4318 0.9525)
			(end -0.4318 -0.9525)
			(stroke
				(width 0)
				(type default)
			)
			(fill no)
			(layer "B.CrtYd")
		)
		(fp_rect
			(start 0.4318 0.9525)
			(end -0.4318 -0.9525)
			(stroke
				(width 0)
				(type default)
			)
			(fill no)
			(layer "B.Fab")
		)
		(pad "1" smd custom
			(at 0 -0.4445 90)
			(size 0.1524 0.1524)
			(layers "B.Cu" "B.Mask" "B.Paste")
			(net "P1V8_C")
			(options
				(clearance outline)
				(anchor circle)
			)
			(primitives
				(gr_poly
					(pts
						(arc
							(start 0.3048 0.2032)
							(mid 0.275042 0.275042)
							(end 0.2032 0.3048)
						)
						(arc
							(start -0.2032 0.3048)
							(mid -0.275042 0.275042)
							(end -0.3048 0.2032)
						)
						(arc
							(start -0.3048 -0.2032)
							(mid -0.275042 -0.275042)
							(end -0.2032 -0.3048)
						)
						(arc
							(start 0.2032 -0.3048)
							(mid 0.275042 -0.275042)
							(end 0.3048 -0.2032)
						)
					)
					(width 0)
					(fill yes)
				)
			)
		)
		(pad "2" smd custom
			(at 0 0.4445 90)
			(size 0.1524 0.1524)
			(layers "B.Cu" "B.Mask" "B.Paste")
			(net "GND")
			(options
				(clearance outline)
				(anchor circle)
			)
			(primitives
				(gr_poly
					(pts
						(arc
							(start 0.3048 0.2032)
							(mid 0.275042 0.275042)
							(end 0.2032 0.3048)
						)
						(arc
							(start -0.2032 0.3048)
							(mid -0.275042 0.275042)
							(end -0.3048 0.2032)
						)
						(arc
							(start -0.3048 -0.2032)
							(mid -0.275042 -0.275042)
							(end -0.2032 -0.3048)
						)
						(arc
							(start 0.2032 -0.3048)
							(mid 0.275042 -0.275042)
							(end 0.3048 -0.2032)
						)
					)
					(width 0)
					(fill yes)
				)
			)
		)
	)
)
